FILE_TYPE = CONNECTIVITY;
{Allegro Design Entry HDL 16.6-p007 (v16-6-112F) 10/10/2012}
"PAGE_NUMBER" = 13;
0"NC";
END.
